#ISCELL
  mstr_misc dns *
  *
#ISCELL
  pure_quanta quanta_title_block_c *
  *
#ISCELL
  standard offpage *
  page270_i1
#ISCELL
  standard offpage *
  page270_i10
#CELL
  pure_quanta q_res *
  page270_i100
#CELL
  pure_quanta q_res *
  page270_i101
#ISCELL
  logical_power universal_gnd *
  page270_i102
#CELL
  pure_quanta q_cap *
  page270_i103
#CELL
  pure_quanta q_cap *
  page270_i104
#ISCELL
  logical_power vcc15 *
  page270_i105
#ISCELL
  standard offpage *
  page270_i106
#ISCELL
  standard offpage *
  page270_i107
#ISCELL
  standard offpage *
  page270_i108
#ISCELL
  standard offpage *
  page270_i109
#ISCELL
  standard offpage *
  page270_i11
#ISCELL
  standard offpage *
  page270_i110
#ISCELL
  standard offpage *
  page270_i111
#ISCELL
  standard offpage *
  page270_i112
#ISCELL
  standard offpage *
  page270_i113
#ISCELL
  standard offpage *
  page270_i114
#ISCELL
  standard offpage *
  page270_i115
#ISCELL
  standard offpage *
  page270_i116
#ISCELL
  standard offpage *
  page270_i117
#ISCELL
  standard offpage *
  page270_i118
#CELL
  pure_quanta q_cap *
  page270_i119
#CELL
  pure_quanta q_res *
  page270_i12
#CELL
  pure_quanta q_cap *
  page270_i120
#CELL
  pure_quanta q_cap *
  page270_i121
#CELL
  pure_quanta q_cap *
  page270_i122
#ISCELL
  logical_power universal_gnd *
  page270_i123
#ISCELL
  standard offpage *
  page270_i124
#ISCELL
  logical_power universal_gnd *
  page270_i125
#CELL
  pure_quanta q_res *
  page270_i126
#ISCELL
  logical_power vcc15 *
  page270_i127
#CELL
  pure_quanta q_cap *
  page270_i128
#ISCELL
  logical_power vcc15 *
  page270_i13
#ISCELL
  logical_power vcc15 *
  page270_i14
#CELL
  pure_quanta q_res *
  page270_i15
#CELL
  pure_quanta q_res *
  page270_i16
#CELL
  pure_quanta q_res *
  page270_i17
#CELL
  pure_quanta q_res *
  page270_i18
#CELL
  pure_quanta q_res *
  page270_i19
#ISCELL
  standard offpage *
  page270_i2
#ISCELL
  standard offpage *
  page270_i20
#ISCELL
  logical_power universal_gnd *
  page270_i21
#CELL
  pure_quanta q_short *
  page270_i22
#CELL
  pure_quanta q_res *
  page270_i23
#ISCELL
  logical_power vcc15 *
  page270_i24
#CELL
  pure_quanta q_res *
  page270_i25
#ISCELL
  logical_power universal_gnd *
  page270_i26
#CELL
  pure_quanta q_res *
  page270_i27
#CELL
  pure_quanta q_cap *
  page270_i28
#CELL
  pure_quanta q_res *
  page270_i29
#ISCELL
  standard offpage *
  page270_i3
#ISCELL
  logical_power universal_gnd *
  page270_i30
#CELL
  pure_quanta q_cap *
  page270_i31
#ISCELL
  logical_power universal_gnd *
  page270_i32
#CELL
  pure_quanta raa229126gnpha0 *
  page270_i33
#CELL
  pure_quanta q_cap *
  page270_i34
#CELL
  pure_quanta q_cap *
  page270_i35
#CELL
  pure_quanta q_res *
  page270_i36
#CELL
  pure_quanta q_res *
  page270_i37
#CELL
  pure_quanta q_cap *
  page270_i38
#ISCELL
  logical_power universal_gnd *
  page270_i39
#CELL
  pure_quanta q_res *
  page270_i4
#ISCELL
  logical_power universal_gnd *
  page270_i40
#ISCELL
  standard offpage *
  page270_i41
#ISCELL
  standard offpage *
  page270_i42
#ISCELL
  standard offpage *
  page270_i43
#ISCELL
  standard offpage *
  page270_i44
#CELL
  pure_quanta q_res *
  page270_i45
#CELL
  pure_quanta q_short *
  page270_i46
#ISCELL
  logical_power universal_gnd *
  page270_i47
#ISCELL
  logical_power vcc15 *
  page270_i48
#CELL
  pure_quanta q_res *
  page270_i49
#ISCELL
  logical_power universal_gnd *
  page270_i5
#ISCELL
  logical_power vcc15 *
  page270_i50
#ISCELL
  standard offpage *
  page270_i51
#ISCELL
  standard offpage *
  page270_i52
#ISCELL
  standard offpage *
  page270_i53
#ISCELL
  standard offpage *
  page270_i54
#ISCELL
  standard offpage *
  page270_i55
#CELL
  pure_quanta q_res *
  page270_i56
#CELL
  pure_quanta q_res *
  page270_i57
#CELL
  pure_quanta q_res *
  page270_i58
#CELL
  pure_quanta q_res *
  page270_i59
#CELL
  pure_quanta q_res *
  page270_i6
#CELL
  pure_quanta q_res *
  page270_i60
#CELL
  pure_quanta q_res *
  page270_i61
#ISCELL
  logical_power vcc15 *
  page270_i62
#CELL
  pure_quanta q_res *
  page270_i63
#CELL
  pure_quanta q_cap *
  page270_i64
#CELL
  pure_quanta q_res *
  page270_i65
#CELL
  pure_quanta q_res *
  page270_i66
#CELL
  pure_quanta q_cap *
  page270_i67
#CELL
  pure_quanta q_cap *
  page270_i68
#ISCELL
  logical_power universal_gnd *
  page270_i69
#CELL
  pure_quanta q_res *
  page270_i7
#ISCELL
  logical_power universal_gnd *
  page270_i70
#ISCELL
  logical_power universal_gnd *
  page270_i71
#CELL
  pure_quanta q_cap *
  page270_i72
#ISCELL
  logical_power universal_gnd *
  page270_i73
#CELL
  pure_quanta q_res *
  page270_i74
#ISCELL
  standard offpage *
  page270_i75
#ISCELL
  standard offpage *
  page270_i76
#ISCELL
  logical_power universal_gnd *
  page270_i77
#ISCELL
  standard offpage *
  page270_i78
#ISCELL
  standard offpage *
  page270_i79
#ISCELL
  logical_power vcc15 *
  page270_i8
#CELL
  pure_quanta q_res *
  page270_i80
#CELL
  pure_quanta q_res *
  page270_i81
#ISCELL
  logical_power universal_gnd *
  page270_i82
#ISCELL
  standard offpage *
  page270_i83
#ISCELL
  standard offpage *
  page270_i84
#ISCELL
  standard offpage *
  page270_i85
#ISCELL
  standard offpage *
  page270_i86
#ISCELL
  standard offpage *
  page270_i87
#ISCELL
  standard offpage *
  page270_i88
#ISCELL
  standard offpage *
  page270_i89
#CELL
  pure_quanta q_res *
  page270_i9
#ISCELL
  standard offpage *
  page270_i90
#ISCELL
  logical_power universal_gnd *
  page270_i91
#CELL
  pure_quanta q_cap *
  page270_i92
#ISCELL
  logical_power universal_gnd *
  page270_i93
#CELL
  pure_quanta q_res *
  page270_i94
#ISCELL
  standard offpage *
  page270_i95
#ISCELL
  standard offpage *
  page270_i96
#ISCELL
  standard offpage *
  page270_i97
#ISCELL
  standard offpage *
  page270_i98
#CELL
  pure_quanta q_res *
  page270_i99
